(kicad_pcb
	(version 20241229)
	(generator "pcbnew")
	(generator_version "9.0")
	(general
		(thickness 1.6642)
		(legacy_teardrops no)
	)
	(paper "A3")
	(title_block
		(title "PolarFire SoM")
		(date "2025-07-22")
		(rev "1.1.4")
		(company "Antmicro Ltd")
		(comment 1 "www.antmicro.com")
		(comment 9 "footprints 40-44 of 470")
	)
	(layers
		(0 "F.Cu" mixed)
		(4 "In1.Cu" power)
		(6 "In2.Cu" signal)
		(8 "In3.Cu" power)
		(10 "In4.Cu" signal)
		(12 "In5.Cu" power)
		(14 "In6.Cu" power)
		(16 "In7.Cu" signal)
		(18 "In8.Cu" power)
		(20 "In9.Cu" signal)
		(22 "In10.Cu" power)
		(24 "In11.Cu" signal)
		(26 "In12.Cu" signal)
		(2 "B.Cu" mixed)
		(9 "F.Adhes" user "F.Adhesive")
		(11 "B.Adhes" user "B.Adhesive")
		(13 "F.Paste" user)
		(15 "B.Paste" user)
		(5 "F.SilkS" user "F.Silkscreen")
		(7 "B.SilkS" user "B.Silkscreen")
		(1 "F.Mask" user)
		(3 "B.Mask" user)
		(17 "Dwgs.User" user "User.Drawings")
		(19 "Cmts.User" user "User.Comments")
		(21 "Eco1.User" user "User.Eco1")
		(23 "Eco2.User" user "User.Eco2")
		(25 "Edge.Cuts" user)
		(27 "Margin" user)
		(31 "F.CrtYd" user "F.Courtyard")
		(29 "B.CrtYd" user "B.Courtyard")
		(35 "F.Fab" user)
		(33 "B.Fab" user)
	)
	(footprint "antmicro-footprints:SOT-523"
		(layer "F.Cu")
		(at 211 147)
		(property "Reference" "Q4"
			(at 0.19 -0.3 0)
			(layer "F.SilkS")
			(effects
				(font
					(size 0.7 0.7)
					(thickness 0.15)
				)
				(justify left bottom)
			)
		)
		(property "Value" "DMG1012T-7"
			(at 0.1 1.824 0)
			(layer "F.Fab")
			(hide yes)
			(effects
				(font
					(size 0.7 0.7)
					(thickness 0.15)
				)
				(justify left bottom)
			)
		)
		(property "Datasheet" "https://www.diodes.com/assets/Datasheets/ds31783.pdf"
			(at 0 0 0)
			(layer "F.Fab")
			(hide yes)
			(effects
				(font
					(size 1.27 1.27)
					(thickness 0.15)
				)
			)
		)
		(property "Description" "Power MOSFET, N Channel, 20 V, 630 mA, 0.3 ohm, SOT-523, Surface Mount"
			(at 0 0 0)
			(layer "F.Fab")
			(hide yes)
			(effects
				(font
					(size 1.27 1.27)
					(thickness 0.15)
				)
			)
		)
		(property "Author" "Antmicro"
			(at 0 0 0)
			(layer "F.Fab")
			(hide yes)
			(effects
				(font
					(size 1 1)
					(thickness 0.15)
				)
			)
		)
		(property "License" "Apache-2.0"
			(at 0 0 0)
			(layer "F.Fab")
			(hide yes)
			(effects
				(font
					(size 1 1)
					(thickness 0.15)
				)
			)
		)
		(property "MPN" "DMG1012T-7"
			(at 0 0 0)
			(layer "F.Fab")
			(hide yes)
			(effects
				(font
					(size 1 1)
					(thickness 0.15)
				)
			)
		)
		(property "Manufacturer" "Diodes Incorporated"
			(at 0 0 0)
			(layer "F.Fab")
			(hide yes)
			(effects
				(font
					(size 1 1)
					(thickness 0.15)
				)
			)
		)
		(property "Public" ""
			(at 0 0 0)
			(layer "F.Fab")
			(hide yes)
			(effects
				(font
					(size 1 1)
					(thickness 0.15)
				)
			)
		)
		(sheetname "/USB/")
		(sheetfile "usb.kicad_sch")
		(attr smd)
		(fp_line
			(start -0.927 -0.351)
			(end -0.725 -0.551)
			(stroke
				(width 0.15)
				(type solid)
			)
			(layer "F.SilkS")
		)
		(fp_line
			(start -0.927 -0.051)
			(end -0.927 -0.351)
			(stroke
				(width 0.15)
				(type solid)
			)
			(layer "F.SilkS")
		)
		(fp_line
			(start -0.725 -0.551)
			(end -0.277 -0.551)
			(stroke
				(width 0.15)
				(type solid)
			)
			(layer "F.SilkS")
		)
		(fp_line
			(start -0.277 -0.551)
			(end -0.277 -0.75)
			(stroke
				(width 0.15)
				(type solid)
			)
			(layer "F.SilkS")
		)
		(fp_circle
			(center -0.9652 0.9652)
			(end -0.9152 0.9652)
			(stroke
				(width 0.15)
				(type solid)
			)
			(fill yes)
			(layer "F.SilkS")
		)
		(fp_line
			(start -1.12 -1.16)
			(end -1.12 1.15)
			(stroke
				(width 0.05)
				(type solid)
			)
			(layer "F.CrtYd")
		)
		(fp_line
			(start -1.12 -1.16)
			(end 1.1 -1.16)
			(stroke
				(width 0.05)
				(type solid)
			)
			(layer "F.CrtYd")
		)
		(fp_line
			(start -1.12 1.15)
			(end 1.1 1.15)
			(stroke
				(width 0.05)
				(type solid)
			)
			(layer "F.CrtYd")
		)
		(fp_line
			(start 1.1 -1.16)
			(end 1.1 1.15)
			(stroke
				(width 0.05)
				(type solid)
			)
			(layer "F.CrtYd")
		)
		(fp_line
			(start -0.802 -0.276)
			(end -0.802 0.424)
			(stroke
				(width 0.15)
				(type solid)
			)
			(layer "F.Fab")
		)
		(fp_line
			(start -0.652 -0.425)
			(end -0.802 -0.276)
			(stroke
				(width 0.15)
				(type solid)
			)
			(layer "F.Fab")
		)
		(fp_line
			(start 0.8 -0.425)
			(end -0.652 -0.425)
			(stroke
				(width 0.15)
				(type solid)
			)
			(layer "F.Fab")
		)
		(fp_line
			(start 0.8 -0.425)
			(end 0.8 0.424)
			(stroke
				(width 0.15)
				(type solid)
			)
			(layer "F.Fab")
		)
		(fp_line
			(start 0.8 0.424)
			(end -0.802 0.424)
			(stroke
				(width 0.15)
				(type solid)
			)
			(layer "F.Fab")
		)
		(fp_circle
			(center -0.9652 0.9652)
			(end -0.9144 0.9652)
			(stroke
				(width 0.15)
				(type solid)
			)
			(fill no)
			(layer "F.Fab")
		)
		(fp_text user "Author: Antmicro"
			(at -1.12 6.224 0)
			(layer "F.Fab")
			(effects
				(font
					(size 0.7 0.7)
					(thickness 0.15)
				)
				(justify left bottom)
			)
		)
		(fp_text user "License: Apache-2.0"
			(at -1.12 5.024 0)
			(layer "F.Fab")
			(effects
				(font
					(size 0.7 0.7)
					(thickness 0.15)
				)
				(justify left bottom)
			)
		)
		(fp_text user "${REFERENCE}"
			(at -1.12 3.824 0)
			(layer "F.Fab")
			(effects
				(font
					(size 0.7 0.7)
					(thickness 0.15)
				)
				(justify left bottom)
			)
		)
		(pad "1" smd rect
			(at -0.5 0.65)
			(size 0.4 0.51)
			(layers "F.Cu" "F.Mask" "F.Paste")
			(net 635 "/FPGA GPIO/ULPI.RESET")
			(pinfunction "G")
			(pintype "input")
		)
		(pad "2" smd rect
			(at 0.498 0.65)
			(size 0.4 0.51)
			(layers "F.Cu" "F.Mask" "F.Paste")
			(net 417 "GND")
			(pinfunction "S")
			(pintype "passive")
		)
		(pad "3" smd rect
			(at 0 -0.652)
			(size 0.4 0.51)
			(layers "F.Cu" "F.Mask" "F.Paste")
			(net 379 "/USB/RESETB")
			(pinfunction "D")
			(pintype "passive")
		)
	)
	(footprint "antmicro-footprints:TP_SMD_0.75mm"
		(layer "F.Cu")
		(at 188.645 116.6)
		(property "Reference" "TP1"
			(at 0 -0.6 0)
			(layer "F.SilkS")
			(hide yes)
			(effects
				(font
					(size 0.7 0.7)
					(thickness 0.15)
				)
				(justify left bottom)
			)
		)
		(property "Value" "TP_0.75mm_SMD"
			(at 0 1.2 0)
			(layer "F.Fab")
			(hide yes)
			(effects
				(font
					(size 0.7 0.7)
					(thickness 0.15)
				)
				(justify left bottom)
			)
		)
		(property "Description" "SMT test point"
			(at 0 0 0)
			(layer "F.Fab")
			(hide yes)
			(effects
				(font
					(size 1.27 1.27)
					(thickness 0.15)
				)
			)
		)
		(property "Author" "Antmicro"
			(at 0 0 0)
			(layer "F.Fab")
			(hide yes)
			(effects
				(font
					(size 1 1)
					(thickness 0.15)
				)
			)
		)
		(property "License" "Apache-2.0"
			(at 0 0 0)
			(layer "F.Fab")
			(hide yes)
			(effects
				(font
					(size 1 1)
					(thickness 0.15)
				)
			)
		)
		(property "MPN" ""
			(at 0 0 0)
			(layer "F.Fab")
			(hide yes)
			(effects
				(font
					(size 1 1)
					(thickness 0.15)
				)
			)
		)
		(property "Manufacturer" ""
			(at 0 0 0)
			(layer "F.Fab")
			(hide yes)
			(effects
				(font
					(size 1 1)
					(thickness 0.15)
				)
			)
		)
		(property "Public" "False"
			(at 0 0 0)
			(layer "F.Fab")
			(hide yes)
			(effects
				(font
					(size 1 1)
					(thickness 0.15)
				)
			)
		)
		(sheetname "/FPGA Config/")
		(sheetfile "fpga-config.kicad_sch")
		(attr exclude_from_pos_files exclude_from_bom)
		(fp_circle
			(center 0 0)
			(end 0.475 0)
			(stroke
				(width 0.05)
				(type default)
			)
			(fill no)
			(layer "F.CrtYd")
		)
		(fp_text user "${REFERENCE}"
			(at -0.4 2.7 0)
			(layer "F.Fab")
			(effects
				(font
					(size 0.7 0.7)
					(thickness 0.15)
				)
				(justify left bottom)
			)
		)
		(fp_text user "License: Apache-2.0"
			(at -0.4 5.101 0)
			(layer "F.Fab")
			(effects
				(font
					(size 0.7 0.7)
					(thickness 0.15)
				)
				(justify left bottom)
			)
		)
		(fp_text user "Author: Antmicro"
			(at -0.4 3.901 0)
			(layer "F.Fab")
			(effects
				(font
					(size 0.7 0.7)
					(thickness 0.15)
				)
				(justify left bottom)
			)
		)
		(pad "1" smd circle
			(at 0 0)
			(size 0.75 0.75)
			(layers "F.Cu" "F.Mask")
			(net 655 "/FPGA Config/DEVRST_N")
			(pinfunction "1")
			(pintype "passive")
		)
	)
	(footprint "antmicro-footprints:TP_SMD_0.75mm"
		(layer "F.Cu")
		(at 228.47 146.545)
		(property "Reference" "TP28"
			(at 9.69 2.225 0)
			(layer "F.SilkS")
			(hide yes)
			(effects
				(font
					(size 0.7 0.7)
					(thickness 0.15)
				)
				(justify left bottom)
			)
		)
		(property "Value" "TP_0.75mm_SMD"
			(at 0 1.2 0)
			(layer "F.Fab")
			(hide yes)
			(effects
				(font
					(size 0.7 0.7)
					(thickness 0.15)
				)
				(justify left bottom)
			)
		)
		(property "Description" "SMT test point"
			(at 0 0 0)
			(layer "F.Fab")
			(hide yes)
			(effects
				(font
					(size 1.27 1.27)
					(thickness 0.15)
				)
			)
		)
		(property "Author" "Antmicro"
			(at 0 0 0)
			(layer "F.Fab")
			(hide yes)
			(effects
				(font
					(size 1 1)
					(thickness 0.15)
				)
			)
		)
		(property "License" "Apache-2.0"
			(at 0 0 0)
			(layer "F.Fab")
			(hide yes)
			(effects
				(font
					(size 1 1)
					(thickness 0.15)
				)
			)
		)
		(property "MPN" ""
			(at 0 0 0)
			(layer "F.Fab")
			(hide yes)
			(effects
				(font
					(size 1 1)
					(thickness 0.15)
				)
			)
		)
		(property "Manufacturer" ""
			(at 0 0 0)
			(layer "F.Fab")
			(hide yes)
			(effects
				(font
					(size 1 1)
					(thickness 0.15)
				)
			)
		)
		(property "Public" "False"
			(at 0 0 0)
			(layer "F.Fab")
			(hide yes)
			(effects
				(font
					(size 1 1)
					(thickness 0.15)
				)
			)
		)
		(sheetname "/WiFi_Bluetooth/")
		(sheetfile "wifi_bt.kicad_sch")
		(attr exclude_from_pos_files exclude_from_bom)
		(fp_circle
			(center 0 0)
			(end 0.475 0)
			(stroke
				(width 0.05)
				(type default)
			)
			(fill no)
			(layer "F.CrtYd")
		)
		(fp_text user "Author: Antmicro"
			(at -0.4 3.901 0)
			(layer "F.Fab")
			(effects
				(font
					(size 0.7 0.7)
					(thickness 0.15)
				)
				(justify left bottom)
			)
		)
		(fp_text user "License: Apache-2.0"
			(at -0.4 5.101 0)
			(layer "F.Fab")
			(effects
				(font
					(size 0.7 0.7)
					(thickness 0.15)
				)
				(justify left bottom)
			)
		)
		(fp_text user "${REFERENCE}"
			(at -0.4 2.7 0)
			(layer "F.Fab")
			(effects
				(font
					(size 0.7 0.7)
					(thickness 0.15)
				)
				(justify left bottom)
			)
		)
		(pad "1" smd circle
			(at 0 0)
			(size 0.75 0.75)
			(layers "F.Cu" "F.Mask")
			(net 525 "Net-(U26A-WL_HOST_WAKE)")
			(pinfunction "1")
			(pintype "passive")
		)
	)
	(footprint "antmicro-footprints:R_0402_1005Metric"
		(layer "F.Cu")
		(at 192.72 118.89 45)
		(descr "Resistor SMD 0402")
		(tags "resistor SMD 0402")
		(property "Reference" "R101"
			(at -1.534422 -0.601041 45)
			(layer "F.SilkS")
			(effects
				(font
					(size 0.7 0.7)
					(thickness 0.15)
				)
				(justify left bottom)
			)
		)
		(property "Value" "R_10k_0402"
			(at -1.011843 1.772046 45)
			(layer "F.Fab")
			(hide yes)
			(effects
				(font
					(size 0.7 0.7)
					(thickness 0.15)
				)
				(justify left bottom)
			)
		)
		(property "Datasheet" "https://www.bourns.com/docs/product-datasheets/cr.pdf"
			(at 0 0 45)
			(layer "F.Fab")
			(hide yes)
			(effects
				(font
					(size 1.27 1.27)
					(thickness 0.15)
				)
			)
		)
		(property "Description" "SMD Chip Resistor, 10 kohm, ± 1%, 62.5 mW, 0402 [1005 Metric], Thick Film, General Purpose"
			(at 0 0 45)
			(layer "F.Fab")
			(hide yes)
			(effects
				(font
					(size 1.27 1.27)
					(thickness 0.15)
				)
			)
		)
		(property "Author" "Antmicro"
			(at 140.514307 -101.451544 0)
			(layer "F.Fab")
			(hide yes)
			(effects
				(font
					(size 1 1)
					(thickness 0.15)
				)
			)
		)
		(property "License" "Apache-2.0"
			(at 140.514307 -101.451544 0)
			(layer "F.Fab")
			(hide yes)
			(effects
				(font
					(size 1 1)
					(thickness 0.15)
				)
			)
		)
		(property "MPN" "CR0402-FX-1002GLF"
			(at 140.514307 -101.451544 0)
			(layer "F.Fab")
			(hide yes)
			(effects
				(font
					(size 1 1)
					(thickness 0.15)
				)
			)
		)
		(property "Manufacturer" "Bourns"
			(at 140.514307 -101.451544 0)
			(layer "F.Fab")
			(hide yes)
			(effects
				(font
					(size 1 1)
					(thickness 0.15)
				)
			)
		)
		(property "Public" ""
			(at 140.514307 -101.451544 0)
			(layer "F.Fab")
			(hide yes)
			(effects
				(font
					(size 1 1)
					(thickness 0.15)
				)
			)
		)
		(property "Tolerance" "1%"
			(at 140.514307 -101.451544 0)
			(layer "F.Fab")
			(hide yes)
			(effects
				(font
					(size 1 1)
					(thickness 0.15)
				)
			)
		)
		(property "Val" "10k"
			(at 140.514307 -101.451544 0)
			(layer "F.Fab")
			(hide yes)
			(effects
				(font
					(size 1 1)
					(thickness 0.15)
				)
			)
		)
		(sheetname "/Top Connector/")
		(sheetfile "top-connector.kicad_sch")
		(attr smd)
		(fp_poly
			(pts
				(xy -0.925 -0.47) (xy 0.925 -0.47) (xy 0.925 0.47) (xy -0.925 0.47)
			)
			(stroke
				(width 0.05)
				(type default)
			)
			(fill no)
			(layer "F.CrtYd")
		)
		(fp_poly
			(pts
				(xy -0.5 -0.25) (xy 0.5 -0.25) (xy 0.5 0.25) (xy -0.5 0.25)
			)
			(stroke
				(width 0.15)
				(type solid)
			)
			(fill no)
			(layer "F.Fab")
		)
		(fp_text user "License: Apache-2.0"
			(at -0.949999 5.169 45)
			(layer "F.Fab")
			(effects
				(font
					(size 0.7 0.7)
					(thickness 0.15)
				)
				(justify left bottom)
			)
		)
		(fp_text user "Author: Antmicro"
			(at -0.95 4.169 45)
			(layer "F.Fab")
			(effects
				(font
					(size 0.7 0.7)
					(thickness 0.15)
				)
				(justify left bottom)
			)
		)
		(fp_text user "${REFERENCE}"
			(at -0.95 3.168 45)
			(layer "F.Fab")
			(effects
				(font
					(size 0.7 0.7)
					(thickness 0.15)
				)
				(justify left bottom)
			)
		)
		(pad "1" smd roundrect
			(at -0.48 0 45)
			(size 0.59 0.64)
			(layers "F.Cu" "F.Mask" "F.Paste")
			(roundrect_rratio 0.25)
			(net 98 "/Top Connector/PI_LED_nPWR")
			(pintype "passive")
		)
		(pad "2" smd roundrect
			(at 0.48 0 45)
			(size 0.59 0.64)
			(layers "F.Cu" "F.Mask" "F.Paste")
			(roundrect_rratio 0.25)
			(net 50 "+3V3")
			(pintype "passive")
		)
	)
	(footprint "antmicro-footprints:C_0402_1005Metric"
		(layer "F.Cu")
		(at 179.718763 147.663922 180)
		(descr "Capacitor SMD 0402")
		(tags "capacitor SMD 0402")
		(property "Reference" "C94"
			(at 0.808763 0.303922 90)
			(layer "F.SilkS")
			(effects
				(font
					(size 0.7 0.7)
					(thickness 0.15)
				)
				(justify right bottom)
			)
		)
		(property "Value" "C_100n_0402"
			(at -1.022927 2.155213 0)
			(layer "F.Fab")
			(hide yes)
			(effects
				(font
					(size 0.7 0.7)
					(thickness 0.15)
				)
				(justify right bottom)
			)
		)
		(property "Datasheet" "https://www.murata.com/products/productdetail?partno=GRM155R61H104KE14%23"
			(at 0 0 180)
			(layer "F.Fab")
			(hide yes)
			(effects
				(font
					(size 1.27 1.27)
					(thickness 0.15)
				)
			)
		)
		(property "Description" "SMD Multilayer Ceramic Capacitor, 0.1 µF, 50 V, 0402 [1005 Metric], ± 10%, X5R, GRM Series"
			(at 0 0 180)
			(layer "F.Fab")
			(hide yes)
			(effects
				(font
					(size 1.27 1.27)
					(thickness 0.15)
				)
			)
		)
		(property "Author" "Antmicro"
			(at 359.437526 295.327844 0)
			(layer "F.Fab")
			(hide yes)
			(effects
				(font
					(size 1 1)
					(thickness 0.15)
				)
			)
		)
		(property "Dielectric" "X5R"
			(at 359.437526 295.327844 0)
			(layer "F.Fab")
			(hide yes)
			(effects
				(font
					(size 1 1)
					(thickness 0.15)
				)
			)
		)
		(property "License" "Apache-2.0"
			(at 359.437526 295.327844 0)
			(layer "F.Fab")
			(hide yes)
			(effects
				(font
					(size 1 1)
					(thickness 0.15)
				)
			)
		)
		(property "MPN" "GRM155R61H104KE14D"
			(at 359.437526 295.327844 0)
			(layer "F.Fab")
			(hide yes)
			(effects
				(font
					(size 1 1)
					(thickness 0.15)
				)
			)
		)
		(property "Manufacturer" "Murata"
			(at 359.437526 295.327844 0)
			(layer "F.Fab")
			(hide yes)
			(effects
				(font
					(size 1 1)
					(thickness 0.15)
				)
			)
		)
		(property "Public" ""
			(at 359.437526 295.327844 0)
			(layer "F.Fab")
			(hide yes)
			(effects
				(font
					(size 1 1)
					(thickness 0.15)
				)
			)
		)
		(property "Val" "100n"
			(at 359.437526 295.327844 0)
			(layer "F.Fab")
			(hide yes)
			(effects
				(font
					(size 1 1)
					(thickness 0.15)
				)
			)
		)
		(property "Voltage" "50V"
			(at 359.437526 295.327844 0)
			(layer "F.Fab")
			(hide yes)
			(effects
				(font
					(size 1 1)
					(thickness 0.15)
				)
			)
		)
		(sheetname "/Supply/")
		(sheetfile "supply.kicad_sch")
		(attr smd)
		(fp_rect
			(start -0.925 -0.47)
			(end 0.925 0.47)
			(stroke
				(width 0.05)
				(type default)
			)
			(fill no)
			(layer "F.CrtYd")
		)
		(fp_line
			(start 0.504 0.248)
			(end -0.494 0.248)
			(stroke
				(width 0.15)
				(type solid)
			)
			(layer "F.Fab")
		)
		(fp_line
			(start 0.504 -0.25)
			(end 0.504 0.248)
			(stroke
				(width 0.15)
				(type solid)
			)
			(layer "F.Fab")
		)
		(fp_line
			(start -0.494 0.248)
			(end -0.494 -0.25)
			(stroke
				(width 0.15)
				(type solid)
			)
			(layer "F.Fab")
		)
		(fp_line
			(start -0.494 -0.25)
			(end 0.504 -0.25)
			(stroke
				(width 0.15)
				(type solid)
			)
			(layer "F.Fab")
		)
		(fp_text user "License: Apache-2.0"
			(at -0.939 5.799 180)
			(layer "F.Fab")
			(effects
				(font
					(size 0.7 0.7)
					(thickness 0.15)
				)
				(justify left bottom)
			)
		)
		(fp_text user "${REFERENCE}"
			(at -0.939 4.599 180)
			(layer "F.Fab")
			(effects
				(font
					(size 0.7 0.7)
					(thickness 0.15)
				)
				(justify left bottom)
			)
		)
		(fp_text user "Author: Antmicro"
			(at -0.939 3.399 180)
			(layer "F.Fab")
			(effects
				(font
					(size 0.7 0.7)
					(thickness 0.15)
				)
				(justify left bottom)
			)
		)
		(pad "1" smd roundrect
			(at -0.48 0 180)
			(size 0.59 0.64)
			(layers "F.Cu" "F.Mask" "F.Paste")
			(roundrect_rratio 0.25)
			(net 417 "GND")
			(pintype "passive")
		)
		(pad "2" smd roundrect
			(at 0.48 0 180)
			(size 0.59 0.64)
			(layers "F.Cu" "F.Mask" "F.Paste")
			(roundrect_rratio 0.25)
			(net 90 "+5V")
			(pintype "passive")
		)
	)
)
